(kicad_pcb
	(version 20260206)
	(generator "pcbnew")
	(generator_version "10.0")
	(general
		(thickness 1.6)
		(legacy_teardrops no)
	)
	(paper "A4")
	(title_block
		(title "v1-chassis-manager — T6M_CM_d_v01_1031_1645.brd")
		(comment 1 "Open CloudServer (Microsoft) / footprints 36-42 of 2512")
	)
	(layers
		(0 "F.Cu" signal "TOP")
		(4 "In1.Cu" signal "GND1")
		(6 "In2.Cu" signal "IN1")
		(8 "In3.Cu" signal "VCC1")
		(10 "In4.Cu" signal "VCC2")
		(12 "In5.Cu" signal "GND2")
		(14 "In6.Cu" signal "IN2")
		(16 "In7.Cu" signal "IN3")
		(18 "In8.Cu" signal "GND3")
		(2 "B.Cu" signal "BOTTOM")
		(9 "F.Adhes" user "F.Adhesive")
		(11 "B.Adhes" user "B.Adhesive")
		(13 "F.Paste" user "Package Geometry/Pastemask Top")
		(15 "B.Paste" user "Package Geometry/Pastemask Bottom")
		(5 "F.SilkS" user "Ref Des/Silkscreen Top")
		(7 "B.SilkS" user "Ref Des/Silkscreen Bottom")
		(1 "F.Mask" user "Board Geometry/Soldermask Top")
		(3 "B.Mask" user "Board Geometry/Soldermask Bottom")
		(17 "Dwgs.User" user "User.Drawings")
		(19 "Cmts.User" user "User.Comments")
		(21 "Eco1.User" user "User.Eco1")
		(23 "Eco2.User" user "User.Eco2")
		(25 "Edge.Cuts" user "Board Geometry/Outline")
		(27 "Margin" user)
		(31 "F.CrtYd" user "Package Geometry/Place Bound Top")
		(29 "B.CrtYd" user "Package Geometry/Place Bound Bottom")
		(35 "F.Fab" user "Ref Des/Assembly Top")
		(33 "B.Fab" user "Ref Des/Assembly Bottom")
	)
	(footprint ""
		(layer "F.Cu")
		(at 21.871178 -160.379156 180)
		(property "Reference" "U137"
			(at 5.163058 8.864092 0)
			(unlocked yes)
			(layer "F.SilkS")
			(effects
				(font
					(size 0.7874 0.5842)
					(thickness 0.1524)
				)
				(justify left)
			)
		)
		(property "Value" ""
			(at 0 0 180)
			(layer "F.Fab")
			(effects
				(font
					(size 1.27 1.27)
				)
			)
		)
		(duplicate_pad_numbers_are_jumpers no)
		(fp_line
			(start 3.564128 7.800086)
			(end -3.564128 7.800086)
			(stroke
				(width 0.1524)
				(type default)
			)
			(layer "F.SilkS")
		)
		(fp_line
			(start 3.564128 -7.800086)
			(end 3.564128 7.800086)
			(stroke
				(width 0.1524)
				(type default)
			)
			(layer "F.SilkS")
		)
		(fp_line
			(start 1.800098 -7.800086)
			(end 3.564128 -7.800086)
			(stroke
				(width 0.1524)
				(type default)
			)
			(layer "F.SilkS")
		)
		(fp_line
			(start 0 -5.999988)
			(end 1.800098 -7.800086)
			(stroke
				(width 0.1524)
				(type default)
			)
			(layer "F.SilkS")
		)
		(fp_line
			(start -1.800098 -7.800086)
			(end 0 -5.999988)
			(stroke
				(width 0.1524)
				(type default)
			)
			(layer "F.SilkS")
		)
		(fp_line
			(start -3.564128 7.800086)
			(end -3.564128 -7.800086)
			(stroke
				(width 0.1524)
				(type default)
			)
			(layer "F.SilkS")
		)
		(fp_line
			(start -3.564128 -7.800086)
			(end -1.800098 -7.800086)
			(stroke
				(width 0.1524)
				(type default)
			)
			(layer "F.SilkS")
		)
		(fp_poly
			(pts
				(xy -6.477 -7.493) (xy -6.477 -6.477) (xy -5.461 -6.985)
			)
			(stroke
				(width 0)
				(type default)
			)
			(fill yes)
			(layer "F.SilkS")
		)
		(fp_poly
			(pts
				(xy -4.249928 7.800086) (xy -4.249928 7.4422) (xy -5.300472 7.4422) (xy -5.300472 -7.4422) (xy -4.249928 -7.4422)
				(xy -4.249928 -7.800086) (xy 4.249928 -7.800086) (xy 4.249928 -7.4422) (xy 5.300472 -7.4422) (xy 5.300472 7.4422)
				(xy 4.249928 7.4422) (xy 4.249928 7.800086)
			)
			(stroke
				(width 0)
				(type default)
			)
			(fill no)
			(layer "F.CrtYd")
		)
		(fp_line
			(start 4.249928 7.800086)
			(end 4.249928 -7.800086)
			(stroke
				(width 0.1)
				(type default)
			)
			(layer "F.Fab")
		)
		(fp_line
			(start 4.249928 -7.800086)
			(end -4.249928 -7.800086)
			(stroke
				(width 0.1)
				(type default)
			)
			(layer "F.Fab")
		)
		(fp_line
			(start -4.249928 7.800086)
			(end 4.249928 7.800086)
			(stroke
				(width 0.1)
				(type default)
			)
			(layer "F.Fab")
		)
		(fp_line
			(start -4.249928 -7.800086)
			(end -4.249928 7.800086)
			(stroke
				(width 0.1)
				(type default)
			)
			(layer "F.Fab")
		)
		(fp_poly
			(pts
				(xy -6.477 -7.493) (xy -6.477 -6.477) (xy -5.461 -6.985)
			)
			(stroke
				(width 0)
				(type default)
			)
			(fill yes)
			(layer "F.Fab")
		)
		(pad "1" smd rect
			(at -4.474972 -6.985 90)
			(size 0.8128 1.5494)
			(layers "F.Cu" "F.Mask" "F.Paste")
			(net "LAN1_MDI0_DP")
		)
		(pad "2" smd rect
			(at -4.474972 -5.715 90)
			(size 0.8128 1.5494)
			(layers "F.Cu" "F.Mask" "F.Paste")
			(net "LAN1_MDI0_DN")
		)
		(pad "3" smd rect
			(at -4.474972 -4.445 90)
			(size 0.8128 1.5494)
			(layers "F.Cu" "F.Mask" "F.Paste")
			(net "P1V9_LAN1")
		)
		(pad "4" smd rect
			(at -4.474972 -3.175 90)
			(size 0.8128 1.5494)
			(layers "F.Cu" "F.Mask" "F.Paste")
			(net "P1V9_LAN1")
		)
		(pad "5" smd rect
			(at -4.474972 -1.905 90)
			(size 0.8128 1.5494)
			(layers "F.Cu" "F.Mask" "F.Paste")
			(net "LAN1_MDI1_DP")
		)
		(pad "6" smd rect
			(at -4.474972 -0.635 90)
			(size 0.8128 1.5494)
			(layers "F.Cu" "F.Mask" "F.Paste")
			(net "LAN1_MDI1_DN")
		)
		(pad "7" smd rect
			(at -4.474972 0.635 90)
			(size 0.8128 1.5494)
			(layers "F.Cu" "F.Mask" "F.Paste")
			(net "LAN1_MDI2_DP")
		)
		(pad "8" smd rect
			(at -4.474972 1.905 90)
			(size 0.8128 1.5494)
			(layers "F.Cu" "F.Mask" "F.Paste")
			(net "LAN1_MDI2_DN")
		)
		(pad "9" smd rect
			(at -4.474972 3.175 90)
			(size 0.8128 1.5494)
			(layers "F.Cu" "F.Mask" "F.Paste")
			(net "P1V9_LAN1")
		)
		(pad "10" smd rect
			(at -4.474972 4.445 90)
			(size 0.8128 1.5494)
			(layers "F.Cu" "F.Mask" "F.Paste")
			(net "P1V9_LAN1")
		)
		(pad "11" smd rect
			(at -4.474972 5.715 90)
			(size 0.8128 1.5494)
			(layers "F.Cu" "F.Mask" "F.Paste")
			(net "LAN1_MDI3_DP")
		)
		(pad "12" smd rect
			(at -4.474972 6.985 90)
			(size 0.8128 1.5494)
			(layers "F.Cu" "F.Mask" "F.Paste")
			(net "LAN1_MDI3_DN")
		)
		(pad "13" smd rect
			(at 4.474972 6.985 90)
			(size 0.8128 1.5494)
			(layers "F.Cu" "F.Mask" "F.Paste")
			(net "LAN1_P4_N")
		)
		(pad "14" smd rect
			(at 4.474972 5.715 90)
			(size 0.8128 1.5494)
			(layers "F.Cu" "F.Mask" "F.Paste")
			(net "LAN1_P4_P")
		)
		(pad "15" smd rect
			(at 4.474972 4.445 90)
			(size 0.8128 1.5494)
			(layers "F.Cu" "F.Mask" "F.Paste")
			(net "LAN1_P4_R")
		)
		(pad "16" smd rect
			(at 4.474972 3.175 90)
			(size 0.8128 1.5494)
			(layers "F.Cu" "F.Mask" "F.Paste")
			(net "LAN1_P3_R")
		)
		(pad "17" smd rect
			(at 4.474972 1.905 90)
			(size 0.8128 1.5494)
			(layers "F.Cu" "F.Mask" "F.Paste")
			(net "LAN1_P3_N")
		)
		(pad "18" smd rect
			(at 4.474972 0.635 90)
			(size 0.8128 1.5494)
			(layers "F.Cu" "F.Mask" "F.Paste")
			(net "LAN1_P3_P")
		)
		(pad "19" smd rect
			(at 4.474972 -0.635 90)
			(size 0.8128 1.5494)
			(layers "F.Cu" "F.Mask" "F.Paste")
			(net "LAN1_P2_N")
		)
		(pad "20" smd rect
			(at 4.474972 -1.905 90)
			(size 0.8128 1.5494)
			(layers "F.Cu" "F.Mask" "F.Paste")
			(net "LAN1_P2_P")
		)
		(pad "21" smd rect
			(at 4.474972 -3.175 90)
			(size 0.8128 1.5494)
			(layers "F.Cu" "F.Mask" "F.Paste")
			(net "LAN1_P2_R")
		)
		(pad "22" smd rect
			(at 4.474972 -4.445 90)
			(size 0.8128 1.5494)
			(layers "F.Cu" "F.Mask" "F.Paste")
			(net "LAN1_P1_R")
		)
		(pad "23" smd rect
			(at 4.474972 -5.715 90)
			(size 0.8128 1.5494)
			(layers "F.Cu" "F.Mask" "F.Paste")
			(net "LAN1_P1_N")
		)
		(pad "24" smd rect
			(at 4.474972 -6.985 90)
			(size 0.8128 1.5494)
			(layers "F.Cu" "F.Mask" "F.Paste")
			(net "LAN1_P1_P")
		)
	)
	(footprint ""
		(layer "F.Cu")
		(at 26.91892 -135.941308 180)
		(property "Reference" "C432"
			(at -0.07112 -1.40716 0)
			(unlocked yes)
			(layer "F.SilkS")
			(effects
				(font
					(size 0.7874 0.5842)
					(thickness 0.1524)
				)
			)
		)
		(property "Value" ""
			(at 0 0 180)
			(layer "F.Fab")
			(effects
				(font
					(size 1.27 1.27)
				)
			)
		)
		(duplicate_pad_numbers_are_jumpers no)
		(fp_line
			(start 1.2954 0.5842)
			(end -1.2954 0.5842)
			(stroke
				(width 0.1524)
				(type default)
			)
			(layer "F.SilkS")
		)
		(fp_line
			(start 1.2954 -0.5842)
			(end 1.2954 0.5842)
			(stroke
				(width 0.1524)
				(type default)
			)
			(layer "F.SilkS")
		)
		(fp_line
			(start 0 -0.5842)
			(end 0 0.5842)
			(stroke
				(width 0.1524)
				(type default)
			)
			(layer "F.SilkS")
		)
		(fp_line
			(start -1.2954 0.5842)
			(end -1.2954 -0.5842)
			(stroke
				(width 0.1524)
				(type default)
			)
			(layer "F.SilkS")
		)
		(fp_line
			(start -1.2954 -0.5842)
			(end 1.2954 -0.5842)
			(stroke
				(width 0.1524)
				(type default)
			)
			(layer "F.SilkS")
		)
		(fp_poly
			(pts
				(xy 0.8636 -0.4572) (xy 0.8636 -0.3556) (xy 1.143 -0.3556) (xy 1.143 0.3556) (xy 0.8636 0.3556)
				(xy 0.8636 0.4572) (xy -0.8636 0.4572) (xy -0.8636 0.3556) (xy -1.143 0.3556) (xy -1.143 -0.3556)
				(xy -0.8636 -0.3556) (xy -0.8636 -0.4572)
			)
			(stroke
				(width 0)
				(type default)
			)
			(fill no)
			(layer "F.CrtYd")
		)
		(fp_line
			(start 0.884936 0.504952)
			(end -0.884936 0.504952)
			(stroke
				(width 0.1)
				(type default)
			)
			(layer "F.Fab")
		)
		(fp_line
			(start 0.884936 -0.504952)
			(end 0.884936 0.504952)
			(stroke
				(width 0.1)
				(type default)
			)
			(layer "F.Fab")
		)
		(fp_line
			(start -0.884936 0.504952)
			(end -0.884936 -0.504952)
			(stroke
				(width 0.1)
				(type default)
			)
			(layer "F.Fab")
		)
		(fp_line
			(start -0.884936 -0.504952)
			(end 0.884936 -0.504952)
			(stroke
				(width 0.1)
				(type default)
			)
			(layer "F.Fab")
		)
		(pad "1" smd rect
			(at 0.7366 0 270)
			(size 0.7112 0.8128)
			(layers "F.Cu" "F.Mask" "F.Paste")
			(net "P1V9_LAN1")
		)
		(pad "2" smd rect
			(at -0.7366 0 270)
			(size 0.7112 0.8128)
			(layers "F.Cu" "F.Mask" "F.Paste")
			(net "GND")
		)
	)
	(footprint ""
		(layer "F.Cu")
		(at 15.284958 -62.089538 -90)
		(property "Reference" "R635"
			(at 0.357886 1.025144 90)
			(unlocked yes)
			(layer "F.SilkS")
			(effects
				(font
					(size 0.7874 0.5842)
					(thickness 0.1524)
				)
				(justify left)
			)
		)
		(property "Value" ""
			(at 0 0 270)
			(layer "F.Fab")
			(effects
				(font
					(size 1.27 1.27)
				)
			)
		)
		(duplicate_pad_numbers_are_jumpers no)
		(fp_line
			(start -0.7874 0.4064)
			(end -0.7874 -0.4064)
			(stroke
				(width 0.1524)
				(type default)
			)
			(layer "F.SilkS")
		)
		(fp_line
			(start 0.7874 0.4064)
			(end -0.7874 0.4064)
			(stroke
				(width 0.1524)
				(type default)
			)
			(layer "F.SilkS")
		)
		(fp_line
			(start -0.7874 -0.4064)
			(end 0.7874 -0.4064)
			(stroke
				(width 0.1524)
				(type default)
			)
			(layer "F.SilkS")
		)
		(fp_line
			(start 0.7874 -0.4064)
			(end 0.7874 0.4064)
			(stroke
				(width 0.1524)
				(type default)
			)
			(layer "F.SilkS")
		)
		(fp_poly
			(pts
				(xy -0.508 0.2794) (xy -0.508 0.2286) (xy -0.635 0.2286) (xy -0.635 -0.254) (xy -0.5334 -0.254)
				(xy -0.5334 -0.2794) (xy 0.5334 -0.2794) (xy 0.5334 -0.254) (xy 0.635 -0.254) (xy 0.635 0.254) (xy 0.5334 0.254)
				(xy 0.5334 0.2794)
			)
			(stroke
				(width 0)
				(type default)
			)
			(fill no)
			(layer "F.CrtYd")
		)
		(pad "1" smd rect
			(at 0.40005 0 270)
			(size 0.4572 0.508)
			(layers "F.Cu" "F.Mask" "F.Paste")
			(net "P5V_CRT")
		)
		(pad "2" smd rect
			(at -0.40005 0 270)
			(size 0.4572 0.508)
			(layers "F.Cu" "F.Mask" "F.Paste")
			(net "I2C_VIDREAR_5V_SCL")
		)
	)
	(footprint ""
		(layer "F.Cu")
		(at 119.138192 -39.93769 180)
		(property "Reference" "R618"
			(at 1.03378 -3.443986 0)
			(unlocked yes)
			(layer "F.SilkS")
			(effects
				(font
					(size 0.7874 0.5842)
					(thickness 0.1524)
				)
				(justify left)
			)
		)
		(property "Value" ""
			(at 0 0 180)
			(layer "F.Fab")
			(effects
				(font
					(size 1.27 1.27)
				)
			)
		)
		(duplicate_pad_numbers_are_jumpers no)
		(fp_line
			(start 0.7874 0.4064)
			(end -0.7874 0.4064)
			(stroke
				(width 0.1524)
				(type default)
			)
			(layer "F.SilkS")
		)
		(fp_line
			(start 0.7874 -0.4064)
			(end 0.7874 0.4064)
			(stroke
				(width 0.1524)
				(type default)
			)
			(layer "F.SilkS")
		)
		(fp_line
			(start -0.7874 0.4064)
			(end -0.7874 -0.4064)
			(stroke
				(width 0.1524)
				(type default)
			)
			(layer "F.SilkS")
		)
		(fp_line
			(start -0.7874 -0.4064)
			(end 0.7874 -0.4064)
			(stroke
				(width 0.1524)
				(type default)
			)
			(layer "F.SilkS")
		)
		(fp_poly
			(pts
				(xy -0.508 0.2794) (xy -0.508 0.2286) (xy -0.635 0.2286) (xy -0.635 -0.254) (xy -0.5334 -0.254)
				(xy -0.5334 -0.2794) (xy 0.5334 -0.2794) (xy 0.5334 -0.254) (xy 0.635 -0.254) (xy 0.635 0.254) (xy 0.5334 0.254)
				(xy 0.5334 0.2794)
			)
			(stroke
				(width 0)
				(type default)
			)
			(fill no)
			(layer "F.CrtYd")
		)
		(pad "1" smd rect
			(at 0.40005 0 180)
			(size 0.4572 0.508)
			(layers "F.Cu" "F.Mask" "F.Paste")
			(net "OSC1_48MHZ")
		)
		(pad "2" smd rect
			(at -0.40005 0 180)
			(size 0.4572 0.508)
			(layers "F.Cu" "F.Mask" "F.Paste")
			(net "SIO_CLKIN")
		)
	)
	(footprint ""
		(layer "F.Cu")
		(at 35.991546 -7.212076 -90)
		(property "Reference" "PC86"
			(at 0.612902 9.233408 90)
			(unlocked yes)
			(layer "F.SilkS")
			(effects
				(font
					(size 0.7874 0.5842)
					(thickness 0.1524)
				)
			)
		)
		(property "Value" ""
			(at 0 0 270)
			(layer "F.Fab")
			(effects
				(font
					(size 1.27 1.27)
				)
			)
		)
		(duplicate_pad_numbers_are_jumpers no)
		(fp_line
			(start -1.2954 0.5842)
			(end -1.2954 -0.5842)
			(stroke
				(width 0.1524)
				(type default)
			)
			(layer "F.SilkS")
		)
		(fp_line
			(start 1.2954 0.5842)
			(end -1.2954 0.5842)
			(stroke
				(width 0.1524)
				(type default)
			)
			(layer "F.SilkS")
		)
		(fp_line
			(start -1.2954 -0.5842)
			(end 1.2954 -0.5842)
			(stroke
				(width 0.1524)
				(type default)
			)
			(layer "F.SilkS")
		)
		(fp_line
			(start 0 -0.5842)
			(end 0 0.5842)
			(stroke
				(width 0.1524)
				(type default)
			)
			(layer "F.SilkS")
		)
		(fp_line
			(start 1.2954 -0.5842)
			(end 1.2954 0.5842)
			(stroke
				(width 0.1524)
				(type default)
			)
			(layer "F.SilkS")
		)
		(fp_poly
			(pts
				(xy 0.8636 -0.4572) (xy 0.8636 -0.3556) (xy 1.143 -0.3556) (xy 1.143 0.3556) (xy 0.8636 0.3556)
				(xy 0.8636 0.4572) (xy -0.8636 0.4572) (xy -0.8636 0.3556) (xy -1.143 0.3556) (xy -1.143 -0.3556)
				(xy -0.8636 -0.3556) (xy -0.8636 -0.4572)
			)
			(stroke
				(width 0)
				(type default)
			)
			(fill no)
			(layer "F.CrtYd")
		)
		(fp_line
			(start -0.884936 0.504952)
			(end -0.884936 -0.504952)
			(stroke
				(width 0.1)
				(type default)
			)
			(layer "F.Fab")
		)
		(fp_line
			(start 0.884936 0.504952)
			(end -0.884936 0.504952)
			(stroke
				(width 0.1)
				(type default)
			)
			(layer "F.Fab")
		)
		(fp_line
			(start -0.884936 -0.504952)
			(end 0.884936 -0.504952)
			(stroke
				(width 0.1)
				(type default)
			)
			(layer "F.Fab")
		)
		(fp_line
			(start 0.884936 -0.504952)
			(end 0.884936 0.504952)
			(stroke
				(width 0.1)
				(type default)
			)
			(layer "F.Fab")
		)
		(pad "1" smd rect
			(at 0.7366 0)
			(size 0.7112 0.8128)
			(layers "F.Cu" "F.Mask" "F.Paste")
			(net "GND")
		)
		(pad "2" smd rect
			(at -0.7366 0)
			(size 0.7112 0.8128)
			(layers "F.Cu" "F.Mask" "F.Paste")
			(net "PV_VDDR_NODE1_VREF")
		)
	)
	(footprint ""
		(layer "F.Cu")
		(at 82.53476 -185.205624 -90)
		(property "Reference" "R895"
			(at -4.198112 1.795272 90)
			(unlocked yes)
			(layer "F.SilkS")
			(effects
				(font
					(size 0.7874 0.5842)
					(thickness 0.1524)
				)
				(justify left)
			)
		)
		(property "Value" ""
			(at 0 0 270)
			(layer "F.Fab")
			(effects
				(font
					(size 1.27 1.27)
				)
			)
		)
		(duplicate_pad_numbers_are_jumpers no)
		(fp_line
			(start -0.7874 0.4064)
			(end -0.7874 -0.4064)
			(stroke
				(width 0.1524)
				(type default)
			)
			(layer "F.SilkS")
		)
		(fp_line
			(start 0.7874 0.4064)
			(end -0.7874 0.4064)
			(stroke
				(width 0.1524)
				(type default)
			)
			(layer "F.SilkS")
		)
		(fp_line
			(start -0.7874 -0.4064)
			(end 0.7874 -0.4064)
			(stroke
				(width 0.1524)
				(type default)
			)
			(layer "F.SilkS")
		)
		(fp_line
			(start 0.7874 -0.4064)
			(end 0.7874 0.4064)
			(stroke
				(width 0.1524)
				(type default)
			)
			(layer "F.SilkS")
		)
		(fp_poly
			(pts
				(xy -0.508 0.2794) (xy -0.508 0.2286) (xy -0.635 0.2286) (xy -0.635 -0.254) (xy -0.5334 -0.254)
				(xy -0.5334 -0.2794) (xy 0.5334 -0.2794) (xy 0.5334 -0.254) (xy 0.635 -0.254) (xy 0.635 0.254) (xy 0.5334 0.254)
				(xy 0.5334 0.2794)
			)
			(stroke
				(width 0)
				(type default)
			)
			(fill no)
			(layer "F.CrtYd")
		)
		(pad "1" smd rect
			(at 0.40005 0 270)
			(size 0.4572 0.508)
			(layers "F.Cu" "F.Mask" "F.Paste")
			(net "T4_NODE1_EN")
		)
		(pad "2" smd rect
			(at -0.40005 0 270)
			(size 0.4572 0.508)
			(layers "F.Cu" "F.Mask" "F.Paste")
			(net "T4_NODE1_EN_R")
		)
	)
	(footprint ""
		(layer "F.Cu")
		(at 37.48786 -164.561012 -90)
		(property "Reference" ""
			(at 0 0 270)
			(layer "F.SilkS")
			(hide yes)
			(effects
				(font
					(size 1.27 1.27)
				)
			)
		)
		(property "Value" ""
			(at 0 0 270)
			(layer "F.Fab")
			(effects
				(font
					(size 1.27 1.27)
				)
			)
		)
		(duplicate_pad_numbers_are_jumpers no)
		(fp_poly
			(pts
				(arc
					(start 0 -1.4986)
					(mid 0 1.4986)
					(end 0 -1.4986)
				)
			)
			(stroke
				(width 0)
				(type default)
			)
			(fill no)
			(layer "F.CrtYd")
		)
		(pad "1" smd circle
			(at 0 0 270)
			(size 0.9906 0.9906)
			(layers "F.Cu" "F.Mask" "F.Paste")
			(net "Net_35")
		)
		(zone
			(layer "F.Cu")
			(hatch none 0.5)
			(connect_pads
				(clearance 0)
			)
			(min_thickness 0.25)
			(keepout
				(tracks not_allowed)
				(vias allowed)
				(pads allowed)
				(copperpour not_allowed)
				(footprints allowed)
			)
			(placement
				(enabled no)
				(sheetname "")
			)
			(fill
				(thermal_gap 0.5)
				(thermal_bridge_width 0.5)
				(island_removal_mode 0)
			)
			(polygon
				(pts
					(arc
						(start 39.11346 -164.561012)
						(mid 35.86226 -164.561012)
						(end 39.11346 -164.561012)
					)
				)
			)
		)
	)
)
